# T6G (Grand Teton) — schematic netlist excerpt (pin names and nets, part order shuffled) for the footprints in the layout excerpt that follows; sources: Cadence DE-HDL packaged netlist, KiCad conversion of 04192023_DAF0TMB3IC0_F0TG_MB_C_brd_V02_OCP.brd

R3714  Q_RES  0 5% CHIP  pkg 0402LF  page 252 : A = SMB_VR_3V3AUX_SDA_R6 ; B = SMB_VR_3V3AUX_SDA
C1707  Q_CAP  0.1UF 25V 10% X7R  pkg 0402  page 248 : A = P3V3_AUX ; B = GND
C401  Q_CAP  100UF 4V 20% X6S  pkg C0805  page 345 : A = P0V9_CPU1_RT2_2A ; B = GND

(kicad_pcb
	(version 20260206)
	(generator "pcbnew")
	(generator_version "10.0")
	(general
		(thickness 1.6)
		(legacy_teardrops no)
	)
	(paper "A4")
	(title_block
		(title "04192023_DAF0TMB3IC0_F0TG_MB_C_brd_V02_OCP.brd")
		(comment 1 "Grand Teton / footprints 1841-1843 of 8354")
	)
	(layers
		(0 "F.Cu" signal "TOP")
		(4 "In1.Cu" signal "GND")
		(6 "In2.Cu" signal "IN1")
		(8 "In3.Cu" signal "GND1")
		(10 "In4.Cu" signal "IN2")
		(12 "In5.Cu" signal "GND2")
		(14 "In6.Cu" signal "IN3")
		(16 "In7.Cu" signal "GND3")
		(18 "In8.Cu" signal "VCC")
		(20 "In9.Cu" signal "VCC1")
		(22 "In10.Cu" signal "GND4")
		(24 "In11.Cu" signal "IN4")
		(26 "In12.Cu" signal "GND5")
		(28 "In13.Cu" signal "IN5")
		(30 "In14.Cu" signal "GND6")
		(32 "In15.Cu" signal "IN6")
		(34 "In16.Cu" signal "GND7")
		(2 "B.Cu" signal "BOTTOM")
		(9 "F.Adhes" user "F.Adhesive")
		(11 "B.Adhes" user "B.Adhesive")
		(13 "F.Paste" user "Package Geometry/Pastemask Top")
		(15 "B.Paste" user "Package Geometry/Pastemask Bottom")
		(5 "F.SilkS" user "Ref Des/Silkscreen Top")
		(7 "B.SilkS" user "Ref Des/Silkscreen Bottom")
		(1 "F.Mask" user "Board Geometry/Soldermask Top")
		(3 "B.Mask" user "Board Geometry/Soldermask Bottom")
		(17 "Dwgs.User" user "User.Drawings")
		(19 "Cmts.User" user "User.Comments")
		(21 "Eco1.User" user "User.Eco1")
		(23 "Eco2.User" user "User.Eco2")
		(25 "Edge.Cuts" user "Board Geometry/Outline")
		(27 "Margin" user)
		(31 "F.CrtYd" user "Package Geometry/Place Bound Top")
		(29 "B.CrtYd" user "Package Geometry/Place Bound Bottom")
		(35 "F.Fab" user "Ref Des/Assembly Top")
		(33 "B.Fab" user "Ref Des/Assembly Bottom")
	)
	(footprint ""
		(layer "F.Cu")
		(at 257.242056 -121.95937 180)
		(property "Reference" "R3714"
			(at 0 0 180)
			(layer "F.SilkS")
			(hide yes)
			(effects
				(font
					(size 1.27 1.27)
				)
			)
		)
		(property "Value" ""
			(at 0 0 180)
			(layer "F.Fab")
			(effects
				(font
					(size 1.27 1.27)
				)
			)
		)
		(duplicate_pad_numbers_are_jumpers no)
		(fp_line
			(start 0.7874 0.4064)
			(end -0.7874 0.4064)
			(stroke
				(width 0.1524)
				(type default)
			)
			(layer "F.SilkS")
		)
		(fp_line
			(start 0.7874 -0.4064)
			(end 0.7874 0.4064)
			(stroke
				(width 0.1524)
				(type default)
			)
			(layer "F.SilkS")
		)
		(fp_line
			(start -0.7874 0.4064)
			(end -0.7874 -0.4064)
			(stroke
				(width 0.1524)
				(type default)
			)
			(layer "F.SilkS")
		)
		(fp_line
			(start -0.7874 -0.4064)
			(end 0.7874 -0.4064)
			(stroke
				(width 0.1524)
				(type default)
			)
			(layer "F.SilkS")
		)
		(fp_line
			(start 0.67945 0.3048)
			(end 0.120396 0.3048)
			(stroke
				(width 0.1)
				(type default)
			)
			(layer "F.Fab")
		)
		(fp_line
			(start 0.67945 -0.3048)
			(end 0.67945 0.3048)
			(stroke
				(width 0.1)
				(type default)
			)
			(layer "F.Fab")
		)
		(fp_line
			(start 0.12065 -0.2794)
			(end 0.12065 -0.3048)
			(stroke
				(width 0.1)
				(type default)
			)
			(layer "F.Fab")
		)
		(fp_line
			(start 0.12065 -0.3048)
			(end 0.67945 -0.3048)
			(stroke
				(width 0.1)
				(type default)
			)
			(layer "F.Fab")
		)
		(fp_line
			(start 0.120396 0.3048)
			(end 0.120396 0.2794)
			(stroke
				(width 0.1)
				(type default)
			)
			(layer "F.Fab")
		)
		(fp_line
			(start 0.120396 0.2794)
			(end -0.12065 0.2794)
			(stroke
				(width 0.1)
				(type default)
			)
			(layer "F.Fab")
		)
		(fp_line
			(start -0.12065 0.3048)
			(end -0.67945 0.3048)
			(stroke
				(width 0.1)
				(type default)
			)
			(layer "F.Fab")
		)
		(fp_line
			(start -0.12065 0.2794)
			(end -0.12065 0.3048)
			(stroke
				(width 0.1)
				(type default)
			)
			(layer "F.Fab")
		)
		(fp_line
			(start -0.12065 -0.2794)
			(end 0.12065 -0.2794)
			(stroke
				(width 0.1)
				(type default)
			)
			(layer "F.Fab")
		)
		(fp_line
			(start -0.12065 -0.305054)
			(end -0.12065 -0.2794)
			(stroke
				(width 0.1)
				(type default)
			)
			(layer "F.Fab")
		)
		(fp_line
			(start -0.67945 0.3048)
			(end -0.67945 -0.305054)
			(stroke
				(width 0.1)
				(type default)
			)
			(layer "F.Fab")
		)
		(fp_line
			(start -0.67945 -0.305054)
			(end -0.12065 -0.305054)
			(stroke
				(width 0.1)
				(type default)
			)
			(layer "F.Fab")
		)
		(pad "1" smd circle
			(at -0.40005 0 180)
			(size 0 0)
			(layers "F.Cu" "F.Mask" "F.Paste")
			(net "SMB_VR_3V3AUX_SDA_R6")
		)
		(pad "2" smd circle
			(at 0.40005 0 180)
			(size 0 0)
			(layers "F.Cu" "F.Mask" "F.Paste")
			(net "SMB_VR_3V3AUX_SDA")
		)
	)
	(footprint ""
		(layer "F.Cu")
		(at 161.999676 -436.87238 90)
		(property "Reference" "C1707"
			(at 0 0 90)
			(layer "F.SilkS")
			(hide yes)
			(effects
				(font
					(size 1.27 1.27)
				)
			)
		)
		(property "Value" ""
			(at 0 0 90)
			(layer "F.Fab")
			(effects
				(font
					(size 1.27 1.27)
				)
			)
		)
		(duplicate_pad_numbers_are_jumpers no)
		(fp_line
			(start 0.7874 -0.4064)
			(end 0.7874 0.4064)
			(stroke
				(width 0.1524)
				(type default)
			)
			(layer "F.SilkS")
		)
		(fp_line
			(start -0.7874 -0.4064)
			(end 0.7874 -0.4064)
			(stroke
				(width 0.1524)
				(type default)
			)
			(layer "F.SilkS")
		)
		(fp_line
			(start 0.7874 0.4064)
			(end -0.7874 0.4064)
			(stroke
				(width 0.1524)
				(type default)
			)
			(layer "F.SilkS")
		)
		(fp_line
			(start -0.7874 0.4064)
			(end -0.7874 -0.4064)
			(stroke
				(width 0.1524)
				(type default)
			)
			(layer "F.SilkS")
		)
		(fp_line
			(start -0.12065 -0.305054)
			(end -0.12065 -0.2794)
			(stroke
				(width 0.1)
				(type default)
			)
			(layer "F.Fab")
		)
		(fp_line
			(start -0.67945 -0.305054)
			(end -0.12065 -0.305054)
			(stroke
				(width 0.1)
				(type default)
			)
			(layer "F.Fab")
		)
		(fp_line
			(start 0.67945 -0.3048)
			(end 0.67945 0.3048)
			(stroke
				(width 0.1)
				(type default)
			)
			(layer "F.Fab")
		)
		(fp_line
			(start 0.12065 -0.3048)
			(end 0.67945 -0.3048)
			(stroke
				(width 0.1)
				(type default)
			)
			(layer "F.Fab")
		)
		(fp_line
			(start 0.12065 -0.2794)
			(end 0.12065 -0.3048)
			(stroke
				(width 0.1)
				(type default)
			)
			(layer "F.Fab")
		)
		(fp_line
			(start -0.12065 -0.2794)
			(end 0.12065 -0.2794)
			(stroke
				(width 0.1)
				(type default)
			)
			(layer "F.Fab")
		)
		(fp_line
			(start 0.120396 0.2794)
			(end -0.12065 0.2794)
			(stroke
				(width 0.1)
				(type default)
			)
			(layer "F.Fab")
		)
		(fp_line
			(start -0.12065 0.2794)
			(end -0.12065 0.3048)
			(stroke
				(width 0.1)
				(type default)
			)
			(layer "F.Fab")
		)
		(fp_line
			(start 0.67945 0.3048)
			(end 0.120396 0.3048)
			(stroke
				(width 0.1)
				(type default)
			)
			(layer "F.Fab")
		)
		(fp_line
			(start 0.120396 0.3048)
			(end 0.120396 0.2794)
			(stroke
				(width 0.1)
				(type default)
			)
			(layer "F.Fab")
		)
		(fp_line
			(start -0.12065 0.3048)
			(end -0.67945 0.3048)
			(stroke
				(width 0.1)
				(type default)
			)
			(layer "F.Fab")
		)
		(fp_line
			(start -0.67945 0.3048)
			(end -0.67945 -0.305054)
			(stroke
				(width 0.1)
				(type default)
			)
			(layer "F.Fab")
		)
		(pad "1" smd circle
			(at -0.40005 0 90)
			(size 0 0)
			(layers "F.Cu" "F.Mask" "F.Paste")
			(net "P3V3_AUX")
		)
		(pad "2" smd circle
			(at 0.40005 0 90)
			(size 0 0)
			(layers "F.Cu" "F.Mask" "F.Paste")
			(net "GND")
		)
	)
	(footprint ""
		(layer "F.Cu")
		(at 170.213782 -390.33323)
		(property "Reference" "C401"
			(at 0 0 0)
			(layer "F.SilkS")
			(hide yes)
			(effects
				(font
					(size 1.27 1.27)
				)
			)
		)
		(property "Value" ""
			(at 0 0 0)
			(layer "F.Fab")
			(effects
				(font
					(size 1.27 1.27)
				)
			)
		)
		(duplicate_pad_numbers_are_jumpers no)
		(fp_line
			(start -1.524 -0.762)
			(end 1.524 -0.762)
			(stroke
				(width 0.1524)
				(type default)
			)
			(layer "F.SilkS")
		)
		(fp_line
			(start -1.524 0.762)
			(end -1.524 -0.762)
			(stroke
				(width 0.1524)
				(type default)
			)
			(layer "F.SilkS")
		)
		(fp_line
			(start 1.524 -0.762)
			(end 1.524 0.762)
			(stroke
				(width 0.1524)
				(type default)
			)
			(layer "F.SilkS")
		)
		(fp_line
			(start 1.524 0.762)
			(end -1.524 0.762)
			(stroke
				(width 0.1524)
				(type default)
			)
			(layer "F.SilkS")
		)
		(fp_line
			(start -1.1049 -0.724916)
			(end -1.1049 0.724916)
			(stroke
				(width 0.1)
				(type default)
			)
			(layer "F.Fab")
		)
		(fp_line
			(start -1.1049 0.724916)
			(end 1.1049 0.724916)
			(stroke
				(width 0.1)
				(type default)
			)
			(layer "F.Fab")
		)
		(fp_line
			(start 1.1049 -0.724916)
			(end -1.1049 -0.724916)
			(stroke
				(width 0.1)
				(type default)
			)
			(layer "F.Fab")
		)
		(fp_line
			(start 1.1049 0.724916)
			(end 1.1049 -0.724916)
			(stroke
				(width 0.1)
				(type default)
			)
			(layer "F.Fab")
		)
		(pad "1" smd rect
			(at -0.889 0 180)
			(size 1.016 1.27)
			(layers "F.Cu" "F.Mask" "F.Paste")
			(net "P0V9_CPU1_RT2_2A")
		)
		(pad "2" smd rect
			(at 0.889 0 180)
			(size 1.016 1.27)
			(layers "F.Cu" "F.Mask" "F.Paste")
			(net "GND")
		)
	)
)
